(kicad_pcb
	(version 20260206)
	(generator "pcbnew")
	(generator_version "10.0")
	(general
		(thickness 1.6)
		(legacy_teardrops no)
	)
	(paper "A4")
	(title_block
		(title "Bryce Canyon_IOM_IOC_16318-2_OCP.brd")
		(comment 1 "Bryce Canyon / footprints 836-841 of 1605")
	)
	(layers
		(0 "F.Cu" signal "TOP")
		(4 "In1.Cu" signal "L2GND")
		(6 "In2.Cu" signal "L3")
		(8 "In3.Cu" signal "L4VCC")
		(10 "In4.Cu" signal "L5VCC")
		(12 "In5.Cu" signal "L6")
		(14 "In6.Cu" signal "L7GND")
		(2 "B.Cu" signal "BOTTOM")
		(9 "F.Adhes" user "F.Adhesive")
		(11 "B.Adhes" user "B.Adhesive")
		(13 "F.Paste" user "Package Geometry/Pastemask Top")
		(15 "B.Paste" user "Package Geometry/Pastemask Bottom")
		(5 "F.SilkS" user "Ref Des/Silkscreen Top")
		(7 "B.SilkS" user "Ref Des/Silkscreen Bottom")
		(1 "F.Mask" user "Board Geometry/Soldermask Top")
		(3 "B.Mask" user "Board Geometry/Soldermask Bottom")
		(17 "Dwgs.User" user "User.Drawings")
		(19 "Cmts.User" user "User.Comments")
		(21 "Eco1.User" user "User.Eco1")
		(23 "Eco2.User" user "User.Eco2")
		(25 "Edge.Cuts" user "Board Geometry/Outline")
		(27 "Margin" user)
		(31 "F.CrtYd" user "Package Geometry/Place Bound Top")
		(29 "B.CrtYd" user "Package Geometry/Place Bound Bottom")
		(35 "F.Fab" user "Ref Des/Assembly Top")
		(33 "B.Fab" user "Ref Des/Assembly Bottom")
	)
	(footprint ""
		(layer "F.Cu")
		(at 60.9092 -121.3612 90)
		(property "Reference" "U29"
			(at 0 0 90)
			(layer "F.SilkS")
			(hide yes)
			(effects
				(font
					(size 1.27 1.27)
				)
			)
		)
		(property "Value" "MX25L25635FMI-10G-GP"
			(at 0 -14.6812 90)
			(unlocked yes)
			(layer "F.Fab")
			(hide yes)
			(effects
				(font
					(size 1.016 1.016)
					(thickness 0.1524)
				)
			)
		)
		(property "Device Type" "SOIC16-6H105"
			(at 0 -16.2052 90)
			(unlocked yes)
			(layer "F.Fab")
			(hide yes)
			(effects
				(font
					(size 1.016 1.016)
					(thickness 0.1524)
				)
			)
		)
		(duplicate_pad_numbers_are_jumpers no)
		(fp_line
			(start 4.7498 -3.2258)
			(end 4.7498 3.2258)
			(stroke
				(width 0.1524)
				(type default)
			)
			(layer "F.SilkS")
		)
		(fp_line
			(start -5.588 -3.2258)
			(end 4.7498 -3.2258)
			(stroke
				(width 0.1524)
				(type default)
			)
			(layer "F.SilkS")
		)
		(fp_line
			(start -5.588 -0.50038)
			(end -5.08762 0)
			(stroke
				(width 0.1524)
				(type default)
			)
			(layer "F.SilkS")
		)
		(fp_line
			(start -5.08762 0)
			(end -5.588 0.50038)
			(stroke
				(width 0.1524)
				(type default)
			)
			(layer "F.SilkS")
		)
		(fp_line
			(start 4.7498 3.2258)
			(end -5.588 3.2258)
			(stroke
				(width 0.1524)
				(type default)
			)
			(layer "F.SilkS")
		)
		(fp_line
			(start -5.4102 3.2258)
			(end -5.4102 5.7912)
			(stroke
				(width 0.508)
				(type default)
			)
			(layer "F.SilkS")
		)
		(fp_line
			(start -5.588 3.2258)
			(end -5.588 -3.2258)
			(stroke
				(width 0.1524)
				(type default)
			)
			(layer "F.SilkS")
		)
		(fp_poly
			(pts
				(xy -4.764786 -3.2258) (xy 4.7625 -3.2258) (xy 4.7625 3.2258) (xy -4.764786 3.2258)
			)
			(stroke
				(width 0)
				(type default)
			)
			(fill yes)
			(layer "F.SilkS")
		)
		(fp_poly
			(pts
				(xy -5.6642 6.0452) (xy 5.6642 6.0452) (xy 5.6642 -6.0452) (xy -5.6642 -6.0452)
			)
			(stroke
				(width 0)
				(type default)
			)
			(fill no)
			(layer "F.CrtYd")
		)
		(fp_poly
			(pts
				(xy -5.6642 -6.0452) (xy 5.6642 -6.0452) (xy 5.6642 6.0452) (xy -5.6642 6.0452)
			)
			(stroke
				(width 0)
				(type default)
			)
			(fill no)
			(layer "F.Fab")
		)
		(pad "1" smd rect
			(at -4.445 4.71805 90)
			(size 0.635 1.651)
			(layers "F.Cu" "F.Mask" "F.Paste")
			(net "PU_IBMC_BT_HOLD_N")
		)
		(pad "2" smd rect
			(at -3.175 4.71805 90)
			(size 0.635 1.651)
			(layers "F.Cu" "F.Mask" "F.Paste")
			(net "P3V3_STBY")
		)
		(pad "3" smd rect
			(at -1.905 4.71805 90)
			(size 0.635 1.651)
			(layers "F.Cu" "F.Mask" "F.Paste")
			(net "FLA1_SPI_RST")
		)
		(pad "4" smd rect
			(at -0.635 4.71805 90)
			(size 0.635 1.651)
			(layers "F.Cu" "F.Mask" "F.Paste")
			(net "Net_334")
		)
		(pad "5" smd rect
			(at 0.635 4.71805 90)
			(size 0.635 1.651)
			(layers "F.Cu" "F.Mask" "F.Paste")
			(net "Net_333")
		)
		(pad "6" smd rect
			(at 1.905 4.71805 90)
			(size 0.635 1.651)
			(layers "F.Cu" "F.Mask" "F.Paste")
			(net "Net_332")
		)
		(pad "7" smd rect
			(at 3.175 4.71805 90)
			(size 0.635 1.651)
			(layers "F.Cu" "F.Mask" "F.Paste")
			(net "FLA_CS_1_R")
		)
		(pad "8" smd rect
			(at 4.445 4.71805 90)
			(size 0.635 1.651)
			(layers "F.Cu" "F.Mask" "F.Paste")
			(net "BMC_SPI_MISO_R")
		)
		(pad "9" smd rect
			(at 4.445 -4.71805 90)
			(size 0.635 1.651)
			(layers "F.Cu" "F.Mask" "F.Paste")
			(net "FLA1_WP_N")
		)
		(pad "10" smd rect
			(at 3.175 -4.71805 90)
			(size 0.635 1.651)
			(layers "F.Cu" "F.Mask" "F.Paste")
			(net "GND")
		)
		(pad "11" smd rect
			(at 1.905 -4.71805 90)
			(size 0.635 1.651)
			(layers "F.Cu" "F.Mask" "F.Paste")
			(net "Net_331")
		)
		(pad "12" smd rect
			(at 0.635 -4.71805 90)
			(size 0.635 1.651)
			(layers "F.Cu" "F.Mask" "F.Paste")
			(net "Net_330")
		)
		(pad "13" smd rect
			(at -0.635 -4.71805 90)
			(size 0.635 1.651)
			(layers "F.Cu" "F.Mask" "F.Paste")
			(net "Net_329")
		)
		(pad "14" smd rect
			(at -1.905 -4.71805 90)
			(size 0.635 1.651)
			(layers "F.Cu" "F.Mask" "F.Paste")
			(net "Net_328")
		)
		(pad "15" smd rect
			(at -3.175 -4.71805 90)
			(size 0.635 1.651)
			(layers "F.Cu" "F.Mask" "F.Paste")
			(net "BMC_SPI_MOSI_R")
		)
		(pad "16" smd rect
			(at -4.445 -4.71805 90)
			(size 0.635 1.651)
			(layers "F.Cu" "F.Mask" "F.Paste")
			(net "BMC_SPI_CLK_R")
		)
	)
	(footprint ""
		(layer "F.Cu")
		(at 208.055972 -76.708 90)
		(property "Reference" "C307"
			(at 0 0 90)
			(layer "F.SilkS")
			(hide yes)
			(effects
				(font
					(size 1.27 1.27)
				)
			)
		)
		(property "Value" "SCD01U16V1KX-GP"
			(at -2.8321 -1.7399 90)
			(unlocked yes)
			(layer "F.Fab")
			(hide yes)
			(effects
				(font
					(size 1.016 1.016)
					(thickness 0.1524)
				)
			)
		)
		(property "Device Type" "C0201H13"
			(at -2.8321 -3.2639 90)
			(unlocked yes)
			(layer "F.Fab")
			(hide yes)
			(effects
				(font
					(size 1.016 1.016)
					(thickness 0.1524)
				)
			)
		)
		(duplicate_pad_numbers_are_jumpers no)
		(fp_rect
			(start -0.2794 0.6477)
			(end 0.2794 -0.6477)
			(stroke
				(width 0)
				(type default)
			)
			(fill no)
			(layer "F.CrtYd")
		)
		(fp_rect
			(start -0.2794 0.6477)
			(end 0.2794 -0.6477)
			(stroke
				(width 0)
				(type default)
			)
			(fill no)
			(layer "F.Fab")
		)
		(pad "1" smd custom
			(at 0 -0.2794 90)
			(size 0.0762 0.0762)
			(layers "F.Cu" "F.Mask" "F.Paste")
			(net "PHY_IOC_TO_CON_A_0_DP_C")
			(options
				(clearance outline)
				(anchor circle)
			)
			(primitives
				(gr_poly
					(pts
						(arc
							(start 0.1524 -0.127)
							(mid 0.137521 -0.162921)
							(end 0.1016 -0.1778)
						)
						(arc
							(start -0.1016 -0.1778)
							(mid -0.137521 -0.162921)
							(end -0.1524 -0.127)
						)
						(arc
							(start -0.1524 0.127)
							(mid -0.137521 0.162921)
							(end -0.1016 0.1778)
						)
						(arc
							(start 0.1016 0.1778)
							(mid 0.137521 0.162921)
							(end 0.1524 0.127)
						)
					)
					(width 0)
					(fill yes)
				)
			)
		)
		(pad "2" smd custom
			(at 0 0.2794 90)
			(size 0.0762 0.0762)
			(layers "F.Cu" "F.Mask" "F.Paste")
			(net "PHY_IOC_TO_CON_A_0_DP")
			(options
				(clearance outline)
				(anchor circle)
			)
			(primitives
				(gr_poly
					(pts
						(arc
							(start 0.1524 -0.127)
							(mid 0.137521 -0.162921)
							(end 0.1016 -0.1778)
						)
						(arc
							(start -0.1016 -0.1778)
							(mid -0.137521 -0.162921)
							(end -0.1524 -0.127)
						)
						(arc
							(start -0.1524 0.127)
							(mid -0.137521 0.162921)
							(end -0.1016 0.1778)
						)
						(arc
							(start 0.1016 0.1778)
							(mid 0.137521 0.162921)
							(end 0.1524 0.127)
						)
					)
					(width 0)
					(fill yes)
				)
			)
		)
	)
	(footprint ""
		(layer "F.Cu")
		(at 98.050858 -17.91716 180)
		(property "Reference" "R46"
			(at 0 0 180)
			(layer "F.SilkS")
			(hide yes)
			(effects
				(font
					(size 1.27 1.27)
				)
			)
		)
		(property "Value" "0R2J-2-GP"
			(at 0.064008 -3.993896 180)
			(unlocked yes)
			(layer "F.Fab")
			(hide yes)
			(effects
				(font
					(size 1.016 1.016)
					(thickness 0.1524)
				)
			)
		)
		(property "Device Type" "R402H16"
			(at 0.064008 -5.517896 180)
			(unlocked yes)
			(layer "F.Fab")
			(hide yes)
			(effects
				(font
					(size 1.016 1.016)
					(thickness 0.1524)
				)
			)
		)
		(duplicate_pad_numbers_are_jumpers no)
		(fp_line
			(start 0.508 -0.9398)
			(end -0.508 -0.9398)
			(stroke
				(width 0.1524)
				(type default)
			)
			(layer "F.SilkS")
		)
		(fp_line
			(start -0.508 -0.9398)
			(end -0.508 0.9398)
			(stroke
				(width 0.1524)
				(type default)
			)
			(layer "F.SilkS")
		)
		(fp_rect
			(start -0.508 0.9398)
			(end 0.508 -0.9398)
			(stroke
				(width 0)
				(type default)
			)
			(fill no)
			(layer "F.CrtYd")
		)
		(fp_rect
			(start -0.508 0.9398)
			(end 0.508 -0.9398)
			(stroke
				(width 0)
				(type default)
			)
			(fill no)
			(layer "F.Fab")
		)
		(pad "1" smd custom
			(at 0 -0.4445 180)
			(size 0.1397 0.1397)
			(layers "F.Cu" "F.Mask" "F.Paste")
			(net "USB_P1_F_DN1")
			(options
				(clearance outline)
				(anchor circle)
			)
			(primitives
				(gr_poly
					(pts
						(arc
							(start -0.1778 -0.2794)
							(mid -0.249642 -0.249642)
							(end -0.2794 -0.1778)
						)
						(arc
							(start -0.2794 0.1778)
							(mid -0.249642 0.249642)
							(end -0.1778 0.2794)
						)
						(arc
							(start 0.1778 0.2794)
							(mid 0.249642 0.249642)
							(end 0.2794 0.1778)
						)
						(arc
							(start 0.2794 -0.1778)
							(mid 0.249642 -0.249642)
							(end 0.1778 -0.2794)
						)
					)
					(width 0)
					(fill yes)
				)
			)
		)
		(pad "2" smd custom
			(at 0 0.4445 180)
			(size 0.1397 0.1397)
			(layers "F.Cu" "F.Mask" "F.Paste")
			(net "USB_P1_DN")
			(options
				(clearance outline)
				(anchor circle)
			)
			(primitives
				(gr_poly
					(pts
						(arc
							(start -0.1778 -0.2794)
							(mid -0.249642 -0.249642)
							(end -0.2794 -0.1778)
						)
						(arc
							(start -0.2794 0.1778)
							(mid -0.249642 0.249642)
							(end -0.1778 0.2794)
						)
						(arc
							(start 0.1778 0.2794)
							(mid 0.249642 0.249642)
							(end 0.2794 0.1778)
						)
						(arc
							(start 0.2794 -0.1778)
							(mid 0.249642 -0.249642)
							(end 0.1778 -0.2794)
						)
					)
					(width 0)
					(fill yes)
				)
			)
		)
	)
	(footprint ""
		(layer "F.Cu")
		(at 39.585646 -177.14341 180)
		(property "Reference" "R482"
			(at 0 0 180)
			(layer "F.SilkS")
			(hide yes)
			(effects
				(font
					(size 1.27 1.27)
				)
			)
		)
		(property "Value" "10KR2J-3-GP"
			(at 0.064008 -3.993896 180)
			(unlocked yes)
			(layer "F.Fab")
			(hide yes)
			(effects
				(font
					(size 1.016 1.016)
					(thickness 0.1524)
				)
			)
		)
		(property "Device Type" "R402H16"
			(at 0.064008 -5.517896 180)
			(unlocked yes)
			(layer "F.Fab")
			(hide yes)
			(effects
				(font
					(size 1.016 1.016)
					(thickness 0.1524)
				)
			)
		)
		(duplicate_pad_numbers_are_jumpers no)
		(fp_line
			(start 0.508 -0.9398)
			(end -0.508 -0.9398)
			(stroke
				(width 0.1524)
				(type default)
			)
			(layer "F.SilkS")
		)
		(fp_line
			(start -0.508 -0.9398)
			(end -0.508 0.9398)
			(stroke
				(width 0.1524)
				(type default)
			)
			(layer "F.SilkS")
		)
		(fp_rect
			(start -0.508 0.9398)
			(end 0.508 -0.9398)
			(stroke
				(width 0)
				(type default)
			)
			(fill no)
			(layer "F.CrtYd")
		)
		(fp_rect
			(start -0.508 0.9398)
			(end 0.508 -0.9398)
			(stroke
				(width 0)
				(type default)
			)
			(fill no)
			(layer "F.Fab")
		)
		(pad "1" smd custom
			(at 0 -0.4445 180)
			(size 0.1397 0.1397)
			(layers "F.Cu" "F.Mask" "F.Paste")
			(net "P12V_STBY")
			(options
				(clearance outline)
				(anchor circle)
			)
			(primitives
				(gr_poly
					(pts
						(arc
							(start -0.1778 -0.2794)
							(mid -0.249642 -0.249642)
							(end -0.2794 -0.1778)
						)
						(arc
							(start -0.2794 0.1778)
							(mid -0.249642 0.249642)
							(end -0.1778 0.2794)
						)
						(arc
							(start 0.1778 0.2794)
							(mid 0.249642 0.249642)
							(end 0.2794 0.1778)
						)
						(arc
							(start 0.2794 -0.1778)
							(mid 0.249642 -0.249642)
							(end 0.1778 -0.2794)
						)
					)
					(width 0)
					(fill yes)
				)
			)
		)
		(pad "2" smd custom
			(at 0 0.4445 180)
			(size 0.1397 0.1397)
			(layers "F.Cu" "F.Mask" "F.Paste")
			(net "P3V3_STBY_EN")
			(options
				(clearance outline)
				(anchor circle)
			)
			(primitives
				(gr_poly
					(pts
						(arc
							(start -0.1778 -0.2794)
							(mid -0.249642 -0.249642)
							(end -0.2794 -0.1778)
						)
						(arc
							(start -0.2794 0.1778)
							(mid -0.249642 0.249642)
							(end -0.1778 0.2794)
						)
						(arc
							(start 0.1778 0.2794)
							(mid 0.249642 0.249642)
							(end 0.2794 0.1778)
						)
						(arc
							(start 0.2794 -0.1778)
							(mid 0.249642 -0.249642)
							(end 0.1778 -0.2794)
						)
					)
					(width 0)
					(fill yes)
				)
			)
		)
	)
	(footprint ""
		(layer "F.Cu")
		(at 59.436 -158.623)
		(property "Reference" "R396"
			(at 0 0 0)
			(layer "F.SilkS")
			(hide yes)
			(effects
				(font
					(size 1.27 1.27)
				)
			)
		)
		(property "Value" "4K7R2F-GP"
			(at 0.064008 -3.993896 0)
			(unlocked yes)
			(layer "F.Fab")
			(hide yes)
			(effects
				(font
					(size 1.016 1.016)
					(thickness 0.1524)
				)
			)
		)
		(property "Device Type" "R402H16"
			(at 0.064008 -5.517896 0)
			(unlocked yes)
			(layer "F.Fab")
			(hide yes)
			(effects
				(font
					(size 1.016 1.016)
					(thickness 0.1524)
				)
			)
		)
		(duplicate_pad_numbers_are_jumpers no)
		(fp_line
			(start -0.508 -0.9398)
			(end -0.508 0.9398)
			(stroke
				(width 0.1524)
				(type default)
			)
			(layer "F.SilkS")
		)
		(fp_line
			(start 0.508 -0.9398)
			(end -0.508 -0.9398)
			(stroke
				(width 0.1524)
				(type default)
			)
			(layer "F.SilkS")
		)
		(fp_rect
			(start -0.508 0.9398)
			(end 0.508 -0.9398)
			(stroke
				(width 0)
				(type default)
			)
			(fill no)
			(layer "F.CrtYd")
		)
		(fp_rect
			(start -0.508 0.9398)
			(end 0.508 -0.9398)
			(stroke
				(width 0)
				(type default)
			)
			(fill no)
			(layer "F.Fab")
		)
		(pad "1" smd custom
			(at 0 -0.4445)
			(size 0.1397 0.1397)
			(layers "F.Cu" "F.Mask" "F.Paste")
			(net "GND")
			(options
				(clearance outline)
				(anchor circle)
			)
			(primitives
				(gr_poly
					(pts
						(arc
							(start -0.1778 -0.2794)
							(mid -0.249642 -0.249642)
							(end -0.2794 -0.1778)
						)
						(arc
							(start -0.2794 0.1778)
							(mid -0.249642 0.249642)
							(end -0.1778 0.2794)
						)
						(arc
							(start 0.1778 0.2794)
							(mid 0.249642 0.249642)
							(end 0.2794 0.1778)
						)
						(arc
							(start 0.2794 -0.1778)
							(mid 0.249642 -0.249642)
							(end 0.1778 -0.2794)
						)
					)
					(width 0)
					(fill yes)
				)
			)
		)
		(pad "2" smd custom
			(at 0 0.4445)
			(size 0.1397 0.1397)
			(layers "F.Cu" "F.Mask" "F.Paste")
			(net "MAC2_TXD0")
			(options
				(clearance outline)
				(anchor circle)
			)
			(primitives
				(gr_poly
					(pts
						(arc
							(start -0.1778 -0.2794)
							(mid -0.249642 -0.249642)
							(end -0.2794 -0.1778)
						)
						(arc
							(start -0.2794 0.1778)
							(mid -0.249642 0.249642)
							(end -0.1778 0.2794)
						)
						(arc
							(start 0.1778 0.2794)
							(mid 0.249642 0.249642)
							(end 0.2794 0.1778)
						)
						(arc
							(start 0.2794 -0.1778)
							(mid 0.249642 -0.249642)
							(end 0.1778 -0.2794)
						)
					)
					(width 0)
					(fill yes)
				)
			)
		)
	)
	(footprint ""
		(layer "F.Cu")
		(at 68.5038 -119.4562 -90)
		(property "Reference" "R266"
			(at 0 0 270)
			(layer "F.SilkS")
			(hide yes)
			(effects
				(font
					(size 1.27 1.27)
				)
			)
		)
		(property "Value" "2K2R2J-2-GP"
			(at 0.064008 -3.993896 270)
			(unlocked yes)
			(layer "F.Fab")
			(hide yes)
			(effects
				(font
					(size 1.016 1.016)
					(thickness 0.1524)
				)
			)
		)
		(property "Device Type" "R402H16"
			(at 0.064008 -5.517896 270)
			(unlocked yes)
			(layer "F.Fab")
			(hide yes)
			(effects
				(font
					(size 1.016 1.016)
					(thickness 0.1524)
				)
			)
		)
		(duplicate_pad_numbers_are_jumpers no)
		(fp_line
			(start -0.508 -0.9398)
			(end -0.508 0.9398)
			(stroke
				(width 0.1524)
				(type default)
			)
			(layer "F.SilkS")
		)
		(fp_line
			(start 0.508 -0.9398)
			(end -0.508 -0.9398)
			(stroke
				(width 0.1524)
				(type default)
			)
			(layer "F.SilkS")
		)
		(fp_rect
			(start -0.508 0.9398)
			(end 0.508 -0.9398)
			(stroke
				(width 0)
				(type default)
			)
			(fill no)
			(layer "F.CrtYd")
		)
		(fp_rect
			(start -0.508 0.9398)
			(end 0.508 -0.9398)
			(stroke
				(width 0)
				(type default)
			)
			(fill no)
			(layer "F.Fab")
		)
		(pad "1" smd custom
			(at 0 -0.4445 270)
			(size 0.1397 0.1397)
			(layers "F.Cu" "F.Mask" "F.Paste")
			(net "P3V3_STBY")
			(options
				(clearance outline)
				(anchor circle)
			)
			(primitives
				(gr_poly
					(pts
						(arc
							(start -0.1778 -0.2794)
							(mid -0.249642 -0.249642)
							(end -0.2794 -0.1778)
						)
						(arc
							(start -0.2794 0.1778)
							(mid -0.249642 0.249642)
							(end -0.1778 0.2794)
						)
						(arc
							(start 0.1778 0.2794)
							(mid 0.249642 0.249642)
							(end 0.2794 0.1778)
						)
						(arc
							(start 0.2794 -0.1778)
							(mid 0.249642 -0.249642)
							(end 0.1778 -0.2794)
						)
					)
					(width 0)
					(fill yes)
				)
			)
		)
		(pad "2" smd custom
			(at 0 0.4445 270)
			(size 0.1397 0.1397)
			(layers "F.Cu" "F.Mask" "F.Paste")
			(net "FLA1_SPI_RST")
			(options
				(clearance outline)
				(anchor circle)
			)
			(primitives
				(gr_poly
					(pts
						(arc
							(start -0.1778 -0.2794)
							(mid -0.249642 -0.249642)
							(end -0.2794 -0.1778)
						)
						(arc
							(start -0.2794 0.1778)
							(mid -0.249642 0.249642)
							(end -0.1778 0.2794)
						)
						(arc
							(start 0.1778 0.2794)
							(mid 0.249642 0.249642)
							(end 0.2794 0.1778)
						)
						(arc
							(start 0.2794 -0.1778)
							(mid 0.249642 -0.249642)
							(end 0.1778 -0.2794)
						)
					)
					(width 0)
					(fill yes)
				)
			)
		)
	)
)
